# BASEBOARD_FAB2 (Tioga Pass) — schematic netlist excerpt (pin names and nets, part order shuffled) for the footprints in the layout excerpt that follows; sources: Cadence DE-HDL packaged netlist, KiCad conversion of Wiwynn_Tioga_Pass_MB.brd

EU4D2  NB3W1200L  IC  pkg LCC  page 102
  VDDA  = P3V3_DB1200_A
  GNDA  = GND
  NC(0)  = NC
  \100m_133m_n\  = FM_100M_N
  HBW_BYPASS_LOBW_N  = FM_HBW_BYPASS_LOWBW_N
  PWRGD_PWRDN_N  = FM_DB1200_PWRGD_R
  GND(0)  = GND
  VDDR  = P3V3_DB1200_R
  CLK_INP  = CLK_100M_DB1200_DP
  CLK_INN  = CLK_100M_DB1200_DN
  SA_0  = FM_DB1200_SMB_SA0
  SDA  = SMB_HOST_STBY_LVC3_SDA_R2
  SCL  = SMB_HOST_STBY_LVC3_SCL_R2
  SA_1  = FM_DB1200_SMB_SA1
  NC(2)  = NC
  NC(1)  = NC
  DIF_0P  = CLK_100M_CPU0_BCLK0_R_DP
  DIF_0N  = CLK_100M_CPU0_BCLK0_R_DN
  OE_0_N  = FM_DB1200ZL_BCLKS_EN_N
  OE_1_N  = FM_DB1200ZL_BCLKS_EN_N
  DIF_1P  = CLK_100M_CPU0_BCLK1_R_DP
  DIF_1N  = CLK_100M_CPU0_BCLK1_R_DN
  GND(1)  = GND
  VDD(0)  = P3V3_DB1200
  VDDIO(0)  = P3V3_DB1200
  DIF_2P  = CLK_100M_CPU0_BCLK2_R_DP
  DIF_2N  = CLK_100M_CPU0_BCLK2_R_DN
  OE_2_N  = FM_DB1200ZL_BCLKS_EN_N
  OE_3_N  = FM_CPU0_MCP_CLK_EN_N
  DIF_3P  = CLK_100M_CPU0_PE_REFCLK_R_DP
  DIF_3N  = CLK_100M_CPU0_PE_REFCLK_R_DN
  VDDIO(1)  = P3V3_DB1200
  GND(2)  = GND
  DIF_4P  = CLK_100M_CPU0_RC_REFCLK0_R_DP
  DIF_4N  = CLK_100M_CPU0_RC_REFCLK0_R_DN
  OE_4_N  = FM_CPU0_MCP_CLK_EN_N
  OE_5_N  = FM_CPU0_MCP_CLK_EN_N
  DIF_5P  = CLK_100M_CPU0_RC_REFCLK1_R_DP
  DIF_5N  = CLK_100M_CPU0_RC_REFCLK1_R_DN
  VDD(1)  = P3V3_DB1200
  GND(3)  = GND
  DIF_6P  = CLK_100M_CPU1_BCLK0_R_DP
  DIF_6N  = CLK_100M_CPU1_BCLK0_R_DN
  OE_6_N  = FM_DB1200ZL_BCLKS_EN_N
  OE_7_N  = FM_DB1200ZL_BCLKS_EN_N
  DIF_7P  = CLK_100M_CPU1_BCLK1_R_DP
  DIF_7N  = CLK_100M_CPU1_BCLK1_R_DN
  GND(4)  = GND
  VDDIO(2)  = P3V3_DB1200
  DIF_8P  = CLK_100M_CPU1_BCLK2_R_DP
  DIF_8N  = CLK_100M_CPU1_BCLK2_R_DN
  OE_8_N  = FM_DB1200ZL_BCLKS_EN_N
  OE_9_N  = FM_CPU1_MCP_CLK_EN_N
  DIF_9P  = CLK_100M_CPU1_PE_REFCLK_R_DP
  DIF_9N  = CLK_100M_CPU1_PE_REFCLK_R_DN
  VDDIO(3)  = P3V3_DB1200
  VDD(2)  = P3V3_DB1200
  GND(5)  = GND
  DIF_10P  = CLK_100M_CPU1_RC_REFCLK0_R_DP
  DIF_10N  = CLK_100M_CPU1_RC_REFCLK0_R_DN
  OE_10_N  = FM_CPU1_MCP_CLK_EN_N
  OE_11_N  = FM_CPU1_MCP_CLK_EN_N
  DIF_11P  = CLK_100M_CPU1_RC_REFCLK1_R_DP
  DIF_11N  = CLK_100M_CPU1_RC_REFCLK1_R_DN
  THPAD  = GND

(kicad_pcb
	(version 20260206)
	(generator "pcbnew")
	(generator_version "10.0")
	(general
		(thickness 1.6)
		(legacy_teardrops no)
	)
	(paper "A4")
	(title_block
		(title "Wiwynn_Tioga_Pass_MB.brd")
		(comment 1 "Tioga Pass / footprint 752 of 4770 (EU4D2), pads 1-17 of 65")
	)
	(layers
		(0 "F.Cu" signal "TOP")
		(4 "In1.Cu" signal "L2GND")
		(6 "In2.Cu" signal "L3")
		(8 "In3.Cu" signal "L4GND")
		(10 "In4.Cu" signal "L5")
		(12 "In5.Cu" signal "L6GND")
		(14 "In6.Cu" signal "L7VCC")
		(16 "In7.Cu" signal "L8VCC")
		(18 "In8.Cu" signal "L9GND")
		(20 "In9.Cu" signal "L10")
		(22 "In10.Cu" signal "L11GND")
		(24 "In11.Cu" signal "L12")
		(26 "In12.Cu" signal "L13GND")
		(2 "B.Cu" signal "BOTTOM")
		(9 "F.Adhes" user "F.Adhesive")
		(11 "B.Adhes" user "B.Adhesive")
		(13 "F.Paste" user "Package Geometry/Pastemask Top")
		(15 "B.Paste" user "Package Geometry/Pastemask Bottom")
		(5 "F.SilkS" user "Ref Des/Silkscreen Top")
		(7 "B.SilkS" user "Ref Des/Silkscreen Bottom")
		(1 "F.Mask" user "Board Geometry/Soldermask Top")
		(3 "B.Mask" user "Board Geometry/Soldermask Bottom")
		(17 "Dwgs.User" user "User.Drawings")
		(19 "Cmts.User" user "User.Comments")
		(21 "Eco1.User" user "User.Eco1")
		(23 "Eco2.User" user "User.Eco2")
		(25 "Edge.Cuts" user "Board Geometry/Outline")
		(27 "Margin" user)
		(31 "F.CrtYd" user "Package Geometry/Place Bound Top")
		(29 "B.CrtYd" user "Package Geometry/Place Bound Bottom")
		(35 "F.Fab" user "Ref Des/Assembly Top")
		(33 "B.Fab" user "Ref Des/Assembly Bottom")
	)
	(footprint ""
		(layer "F.Cu")
		(at 169.422826 -80.961992 90)
		(property "Reference" "EU4D2"
			(at -8.471662 1.773174 0)
			(unlocked yes)
			(layer "F.SilkS")
			(effects
				(font
					(size 0.7874 0.5842)
					(thickness 0.1524)
				)
				(justify left)
			)
		)
		(property "Value" ""
			(at 0 0 90)
			(layer "F.Fab")
			(effects
				(font
					(size 1.27 1.27)
				)
			)
		)
		(duplicate_pad_numbers_are_jumpers no)
		(pad "1" smd custom
			(at -4.3688 -3.750818 90)
			(size 0.0762 0.0762)
			(layers "F.Cu" "F.Mask" "F.Paste")
			(net "P3V3_DB1200_A")
			(options
				(clearance outline)
				(anchor circle)
			)
			(primitives
				(gr_poly
					(pts
						(xy -0.381 -0.1524)
						(arc
							(start 0.2286 -0.1524)
							(mid 0.381 0)
							(end 0.2286 0.1524)
						)
						(xy -0.381 0.1524)
					)
					(width 0)
					(fill yes)
				)
			)
		)
		(pad "2" smd custom
			(at -4.3688 -3.250692 90)
			(size 0.0762 0.0762)
			(layers "F.Cu" "F.Mask" "F.Paste")
			(net "GND")
			(options
				(clearance outline)
				(anchor circle)
			)
			(primitives
				(gr_poly
					(pts
						(xy -0.381 -0.1524)
						(arc
							(start 0.2286 -0.1524)
							(mid 0.381 0)
							(end 0.2286 0.1524)
						)
						(xy -0.381 0.1524)
					)
					(width 0)
					(fill yes)
				)
			)
		)
		(pad "3" smd custom
			(at -4.3688 -2.750566 90)
			(size 0.0762 0.0762)
			(layers "F.Cu" "F.Mask" "F.Paste")
			(net "Net_341")
			(options
				(clearance outline)
				(anchor circle)
			)
			(primitives
				(gr_poly
					(pts
						(xy -0.381 -0.1524)
						(arc
							(start 0.2286 -0.1524)
							(mid 0.381 0)
							(end 0.2286 0.1524)
						)
						(xy -0.381 0.1524)
					)
					(width 0)
					(fill yes)
				)
			)
		)
		(pad "4" smd custom
			(at -4.3688 -2.25044 90)
			(size 0.0762 0.0762)
			(layers "F.Cu" "F.Mask" "F.Paste")
			(net "FM_100M_N")
			(options
				(clearance outline)
				(anchor circle)
			)
			(primitives
				(gr_poly
					(pts
						(xy -0.381 -0.1524)
						(arc
							(start 0.2286 -0.1524)
							(mid 0.381 0)
							(end 0.2286 0.1524)
						)
						(xy -0.381 0.1524)
					)
					(width 0)
					(fill yes)
				)
			)
		)
		(pad "5" smd custom
			(at -4.3688 -1.750314 90)
			(size 0.0762 0.0762)
			(layers "F.Cu" "F.Mask" "F.Paste")
			(net "FM_HBW_BYPASS_LOWBW_N")
			(options
				(clearance outline)
				(anchor circle)
			)
			(primitives
				(gr_poly
					(pts
						(xy -0.381 -0.1524)
						(arc
							(start 0.2286 -0.1524)
							(mid 0.381 0)
							(end 0.2286 0.1524)
						)
						(xy -0.381 0.1524)
					)
					(width 0)
					(fill yes)
				)
			)
		)
		(pad "6" smd custom
			(at -4.3688 -1.250188 90)
			(size 0.0762 0.0762)
			(layers "F.Cu" "F.Mask" "F.Paste")
			(net "FM_DB1200_PWRGD_R")
			(options
				(clearance outline)
				(anchor circle)
			)
			(primitives
				(gr_poly
					(pts
						(xy -0.381 -0.1524)
						(arc
							(start 0.2286 -0.1524)
							(mid 0.381 0)
							(end 0.2286 0.1524)
						)
						(xy -0.381 0.1524)
					)
					(width 0)
					(fill yes)
				)
			)
		)
		(pad "7" smd custom
			(at -4.3688 -0.750062 90)
			(size 0.0762 0.0762)
			(layers "F.Cu" "F.Mask" "F.Paste")
			(net "GND")
			(options
				(clearance outline)
				(anchor circle)
			)
			(primitives
				(gr_poly
					(pts
						(xy -0.381 -0.1524)
						(arc
							(start 0.2286 -0.1524)
							(mid 0.381 0)
							(end 0.2286 0.1524)
						)
						(xy -0.381 0.1524)
					)
					(width 0)
					(fill yes)
				)
			)
		)
		(pad "8" smd custom
			(at -4.3688 -0.249936 90)
			(size 0.0762 0.0762)
			(layers "F.Cu" "F.Mask" "F.Paste")
			(net "P3V3_DB1200_R")
			(options
				(clearance outline)
				(anchor circle)
			)
			(primitives
				(gr_poly
					(pts
						(xy -0.381 -0.1524)
						(arc
							(start 0.2286 -0.1524)
							(mid 0.381 0)
							(end 0.2286 0.1524)
						)
						(xy -0.381 0.1524)
					)
					(width 0)
					(fill yes)
				)
			)
		)
		(pad "9" smd custom
			(at -4.3688 0.25019 90)
			(size 0.0762 0.0762)
			(layers "F.Cu" "F.Mask" "F.Paste")
			(net "CLK_100M_DB1200_DP")
			(options
				(clearance outline)
				(anchor circle)
			)
			(primitives
				(gr_poly
					(pts
						(xy -0.381 -0.1524)
						(arc
							(start 0.2286 -0.1524)
							(mid 0.381 0)
							(end 0.2286 0.1524)
						)
						(xy -0.381 0.1524)
					)
					(width 0)
					(fill yes)
				)
			)
		)
		(pad "10" smd custom
			(at -4.3688 0.750316 90)
			(size 0.0762 0.0762)
			(layers "F.Cu" "F.Mask" "F.Paste")
			(net "CLK_100M_DB1200_DN")
			(options
				(clearance outline)
				(anchor circle)
			)
			(primitives
				(gr_poly
					(pts
						(xy -0.381 -0.1524)
						(arc
							(start 0.2286 -0.1524)
							(mid 0.381 0)
							(end 0.2286 0.1524)
						)
						(xy -0.381 0.1524)
					)
					(width 0)
					(fill yes)
				)
			)
		)
		(pad "11" smd custom
			(at -4.3688 1.250442 90)
			(size 0.0762 0.0762)
			(layers "F.Cu" "F.Mask" "F.Paste")
			(net "FM_DB1200_SMB_SA0")
			(options
				(clearance outline)
				(anchor circle)
			)
			(primitives
				(gr_poly
					(pts
						(xy -0.381 -0.1524)
						(arc
							(start 0.2286 -0.1524)
							(mid 0.381 0)
							(end 0.2286 0.1524)
						)
						(xy -0.381 0.1524)
					)
					(width 0)
					(fill yes)
				)
			)
		)
		(pad "12" smd custom
			(at -4.3688 1.750568 90)
			(size 0.0762 0.0762)
			(layers "F.Cu" "F.Mask" "F.Paste")
			(net "SMB_HOST_STBY_LVC3_SDA_R2")
			(options
				(clearance outline)
				(anchor circle)
			)
			(primitives
				(gr_poly
					(pts
						(xy -0.381 -0.1524)
						(arc
							(start 0.2286 -0.1524)
							(mid 0.381 0)
							(end 0.2286 0.1524)
						)
						(xy -0.381 0.1524)
					)
					(width 0)
					(fill yes)
				)
			)
		)
		(pad "13" smd custom
			(at -4.3688 2.250694 90)
			(size 0.0762 0.0762)
			(layers "F.Cu" "F.Mask" "F.Paste")
			(net "SMB_HOST_STBY_LVC3_SCL_R2")
			(options
				(clearance outline)
				(anchor circle)
			)
			(primitives
				(gr_poly
					(pts
						(xy -0.381 -0.1524)
						(arc
							(start 0.2286 -0.1524)
							(mid 0.381 0)
							(end 0.2286 0.1524)
						)
						(xy -0.381 0.1524)
					)
					(width 0)
					(fill yes)
				)
			)
		)
		(pad "14" smd custom
			(at -4.3688 2.75082 90)
			(size 0.0762 0.0762)
			(layers "F.Cu" "F.Mask" "F.Paste")
			(net "FM_DB1200_SMB_SA1")
			(options
				(clearance outline)
				(anchor circle)
			)
			(primitives
				(gr_poly
					(pts
						(xy -0.381 -0.1524)
						(arc
							(start 0.2286 -0.1524)
							(mid 0.381 0)
							(end 0.2286 0.1524)
						)
						(xy -0.381 0.1524)
					)
					(width 0)
					(fill yes)
				)
			)
		)
		(pad "15" smd custom
			(at -4.3688 3.250946 90)
			(size 0.0762 0.0762)
			(layers "F.Cu" "F.Mask" "F.Paste")
			(net "Net_342")
			(options
				(clearance outline)
				(anchor circle)
			)
			(primitives
				(gr_poly
					(pts
						(xy -0.381 -0.1524)
						(arc
							(start 0.2286 -0.1524)
							(mid 0.381 0)
							(end 0.2286 0.1524)
						)
						(xy -0.381 0.1524)
					)
					(width 0)
					(fill yes)
				)
			)
		)
		(pad "16" smd custom
			(at -4.3688 3.751072 90)
			(size 0.0762 0.0762)
			(layers "F.Cu" "F.Mask" "F.Paste")
			(net "Net_343")
			(options
				(clearance outline)
				(anchor circle)
			)
			(primitives
				(gr_poly
					(pts
						(xy -0.381 -0.1524)
						(arc
							(start 0.2286 -0.1524)
							(mid 0.381 0)
							(end 0.2286 0.1524)
						)
						(xy -0.381 0.1524)
					)
					(width 0)
					(fill yes)
				)
			)
		)
		(pad "17" smd custom
			(at -3.750818 4.3688 90)
			(size 0.0762 0.0762)
			(layers "F.Cu" "F.Mask" "F.Paste")
			(net "CLK_100M_CPU0_BCLK0_R_DP")
			(options
				(clearance outline)
				(anchor circle)
			)
			(primitives
				(gr_poly
					(pts
						(xy -0.1524 0.381)
						(arc
							(start -0.1524 -0.2286)
							(mid 0 -0.381)
							(end 0.1524 -0.2286)
						)
						(xy 0.1524 0.381)
					)
					(width 0)
					(fill yes)
				)
			)
		)
	)
)
